(kicad_pcb
	(version 20260206)
	(generator "pcbnew")
	(generator_version "10.0")
	(general
		(thickness 1.6)
		(legacy_teardrops no)
	)
	(paper "A4")
	(title_block
		(title "01162023_DA0F0TEBIF0_F0T_Expander_BD_F_brd_V02_OCP.brd")
		(comment 1 "Grand Teton / footprints 2208-2214 of 9728")
	)
	(layers
		(0 "F.Cu" signal "TOP")
		(4 "In1.Cu" signal "GND")
		(6 "In2.Cu" signal "VCC")
		(8 "In3.Cu" signal "VCC1")
		(10 "In4.Cu" signal "GND1")
		(12 "In5.Cu" signal "IN1")
		(14 "In6.Cu" signal "GND2")
		(16 "In7.Cu" signal "IN2")
		(18 "In8.Cu" signal "GND3")
		(20 "In9.Cu" signal "IN3")
		(22 "In10.Cu" signal "GND4")
		(24 "In11.Cu" signal "IN4")
		(26 "In12.Cu" signal "GND5")
		(28 "In13.Cu" signal "IN5")
		(30 "In14.Cu" signal "GND6")
		(32 "In15.Cu" signal "IN6")
		(34 "In16.Cu" signal "GND7")
		(2 "B.Cu" signal "BOTTOM")
		(9 "F.Adhes" user "F.Adhesive")
		(11 "B.Adhes" user "B.Adhesive")
		(13 "F.Paste" user "Package Geometry/Pastemask Top")
		(15 "B.Paste" user "Package Geometry/Pastemask Bottom")
		(5 "F.SilkS" user "Ref Des/Silkscreen Top")
		(7 "B.SilkS" user "Ref Des/Silkscreen Bottom")
		(1 "F.Mask" user "Board Geometry/Soldermask Top")
		(3 "B.Mask" user "Board Geometry/Soldermask Bottom")
		(17 "Dwgs.User" user "User.Drawings")
		(19 "Cmts.User" user "User.Comments")
		(21 "Eco1.User" user "User.Eco1")
		(23 "Eco2.User" user "User.Eco2")
		(25 "Edge.Cuts" user "Board Geometry/Outline")
		(27 "Margin" user)
		(31 "F.CrtYd" user "Package Geometry/Place Bound Top")
		(29 "B.CrtYd" user "Package Geometry/Place Bound Bottom")
		(35 "F.Fab" user "Ref Des/Assembly Top")
		(33 "B.Fab" user "Ref Des/Assembly Bottom")
	)
	(footprint ""
		(layer "F.Cu")
		(at 329.69835 -66.32194 -90)
		(property "Reference" "PC875"
			(at 0 0 270)
			(layer "F.SilkS")
			(hide yes)
			(effects
				(font
					(size 1.27 1.27)
				)
			)
		)
		(property "Value" ""
			(at 0 0 270)
			(layer "F.Fab")
			(effects
				(font
					(size 1.27 1.27)
				)
			)
		)
		(duplicate_pad_numbers_are_jumpers no)
		(fp_line
			(start -0.7874 0.4064)
			(end -0.7874 -0.4064)
			(stroke
				(width 0.1524)
				(type default)
			)
			(layer "F.SilkS")
		)
		(fp_line
			(start 0.7874 0.4064)
			(end -0.7874 0.4064)
			(stroke
				(width 0.1524)
				(type default)
			)
			(layer "F.SilkS")
		)
		(fp_line
			(start -0.7874 -0.4064)
			(end 0.7874 -0.4064)
			(stroke
				(width 0.1524)
				(type default)
			)
			(layer "F.SilkS")
		)
		(fp_line
			(start 0.7874 -0.4064)
			(end 0.7874 0.4064)
			(stroke
				(width 0.1524)
				(type default)
			)
			(layer "F.SilkS")
		)
		(fp_line
			(start -0.67945 0.3048)
			(end -0.67945 -0.305054)
			(stroke
				(width 0.1)
				(type default)
			)
			(layer "F.Fab")
		)
		(fp_line
			(start -0.12065 0.3048)
			(end -0.67945 0.3048)
			(stroke
				(width 0.1)
				(type default)
			)
			(layer "F.Fab")
		)
		(fp_line
			(start 0.120396 0.3048)
			(end 0.120396 0.2794)
			(stroke
				(width 0.1)
				(type default)
			)
			(layer "F.Fab")
		)
		(fp_line
			(start 0.67945 0.3048)
			(end 0.120396 0.3048)
			(stroke
				(width 0.1)
				(type default)
			)
			(layer "F.Fab")
		)
		(fp_line
			(start -0.12065 0.2794)
			(end -0.12065 0.3048)
			(stroke
				(width 0.1)
				(type default)
			)
			(layer "F.Fab")
		)
		(fp_line
			(start 0.120396 0.2794)
			(end -0.12065 0.2794)
			(stroke
				(width 0.1)
				(type default)
			)
			(layer "F.Fab")
		)
		(fp_line
			(start -0.12065 -0.2794)
			(end 0.12065 -0.2794)
			(stroke
				(width 0.1)
				(type default)
			)
			(layer "F.Fab")
		)
		(fp_line
			(start 0.12065 -0.2794)
			(end 0.12065 -0.3048)
			(stroke
				(width 0.1)
				(type default)
			)
			(layer "F.Fab")
		)
		(fp_line
			(start 0.12065 -0.3048)
			(end 0.67945 -0.3048)
			(stroke
				(width 0.1)
				(type default)
			)
			(layer "F.Fab")
		)
		(fp_line
			(start 0.67945 -0.3048)
			(end 0.67945 0.3048)
			(stroke
				(width 0.1)
				(type default)
			)
			(layer "F.Fab")
		)
		(fp_line
			(start -0.67945 -0.305054)
			(end -0.12065 -0.305054)
			(stroke
				(width 0.1)
				(type default)
			)
			(layer "F.Fab")
		)
		(fp_line
			(start -0.12065 -0.305054)
			(end -0.12065 -0.2794)
			(stroke
				(width 0.1)
				(type default)
			)
			(layer "F.Fab")
		)
		(pad "1" smd circle
			(at -0.40005 0 270)
			(size 0 0)
			(layers "F.Cu" "F.Mask" "F.Paste")
			(net "P12V_SSD11_CO_GATE")
		)
		(pad "2" smd circle
			(at 0.40005 0 270)
			(size 0 0)
			(layers "F.Cu" "F.Mask" "F.Paste")
			(net "GND")
		)
	)
	(footprint ""
		(layer "F.Cu")
		(at 260.249162 -287.395412 -90)
		(property "Reference" "C3402"
			(at 0 0 270)
			(layer "F.SilkS")
			(hide yes)
			(effects
				(font
					(size 1.27 1.27)
				)
			)
		)
		(property "Value" ""
			(at 0 0 270)
			(layer "F.Fab")
			(effects
				(font
					(size 1.27 1.27)
				)
			)
		)
		(duplicate_pad_numbers_are_jumpers no)
		(fp_line
			(start -0.299974 0.150114)
			(end -0.299974 -0.150114)
			(stroke
				(width 0.1)
				(type default)
			)
			(layer "F.Fab")
		)
		(fp_line
			(start 0.299974 0.150114)
			(end -0.299974 0.150114)
			(stroke
				(width 0.1)
				(type default)
			)
			(layer "F.Fab")
		)
		(fp_line
			(start -0.299974 -0.150114)
			(end 0.299974 -0.150114)
			(stroke
				(width 0.1)
				(type default)
			)
			(layer "F.Fab")
		)
		(fp_line
			(start 0.299974 -0.150114)
			(end 0.299974 0.150114)
			(stroke
				(width 0.1)
				(type default)
			)
			(layer "F.Fab")
		)
		(pad "1" smd rect
			(at -0.2667 0 270)
			(size 0.3048 0.381)
			(layers "F.Cu" "F.Mask" "F.Paste")
			(net "P1V8_PLL0_PEX2")
		)
		(pad "2" smd rect
			(at 0.2667 0 270)
			(size 0.3048 0.381)
			(layers "F.Cu" "F.Mask" "F.Paste")
			(net "GND")
		)
	)
	(footprint ""
		(layer "F.Cu")
		(at 329.438 -83.82 180)
		(property "Reference" "R1472"
			(at 0 0 180)
			(layer "F.SilkS")
			(hide yes)
			(effects
				(font
					(size 1.27 1.27)
				)
			)
		)
		(property "Value" ""
			(at 0 0 180)
			(layer "F.Fab")
			(effects
				(font
					(size 1.27 1.27)
				)
			)
		)
		(duplicate_pad_numbers_are_jumpers no)
		(fp_line
			(start 0.7874 0.4064)
			(end -0.7874 0.4064)
			(stroke
				(width 0.1524)
				(type default)
			)
			(layer "F.SilkS")
		)
		(fp_line
			(start 0.7874 -0.4064)
			(end 0.7874 0.4064)
			(stroke
				(width 0.1524)
				(type default)
			)
			(layer "F.SilkS")
		)
		(fp_line
			(start -0.7874 0.4064)
			(end -0.7874 -0.4064)
			(stroke
				(width 0.1524)
				(type default)
			)
			(layer "F.SilkS")
		)
		(fp_line
			(start -0.7874 -0.4064)
			(end 0.7874 -0.4064)
			(stroke
				(width 0.1524)
				(type default)
			)
			(layer "F.SilkS")
		)
		(fp_line
			(start 0.67945 0.3048)
			(end 0.120396 0.3048)
			(stroke
				(width 0.1)
				(type default)
			)
			(layer "F.Fab")
		)
		(fp_line
			(start 0.67945 -0.3048)
			(end 0.67945 0.3048)
			(stroke
				(width 0.1)
				(type default)
			)
			(layer "F.Fab")
		)
		(fp_line
			(start 0.12065 -0.2794)
			(end 0.12065 -0.3048)
			(stroke
				(width 0.1)
				(type default)
			)
			(layer "F.Fab")
		)
		(fp_line
			(start 0.12065 -0.3048)
			(end 0.67945 -0.3048)
			(stroke
				(width 0.1)
				(type default)
			)
			(layer "F.Fab")
		)
		(fp_line
			(start 0.120396 0.3048)
			(end 0.120396 0.2794)
			(stroke
				(width 0.1)
				(type default)
			)
			(layer "F.Fab")
		)
		(fp_line
			(start 0.120396 0.2794)
			(end -0.12065 0.2794)
			(stroke
				(width 0.1)
				(type default)
			)
			(layer "F.Fab")
		)
		(fp_line
			(start -0.12065 0.3048)
			(end -0.67945 0.3048)
			(stroke
				(width 0.1)
				(type default)
			)
			(layer "F.Fab")
		)
		(fp_line
			(start -0.12065 0.2794)
			(end -0.12065 0.3048)
			(stroke
				(width 0.1)
				(type default)
			)
			(layer "F.Fab")
		)
		(fp_line
			(start -0.12065 -0.2794)
			(end 0.12065 -0.2794)
			(stroke
				(width 0.1)
				(type default)
			)
			(layer "F.Fab")
		)
		(fp_line
			(start -0.12065 -0.305054)
			(end -0.12065 -0.2794)
			(stroke
				(width 0.1)
				(type default)
			)
			(layer "F.Fab")
		)
		(fp_line
			(start -0.67945 0.3048)
			(end -0.67945 -0.305054)
			(stroke
				(width 0.1)
				(type default)
			)
			(layer "F.Fab")
		)
		(fp_line
			(start -0.67945 -0.305054)
			(end -0.12065 -0.305054)
			(stroke
				(width 0.1)
				(type default)
			)
			(layer "F.Fab")
		)
		(pad "1" smd circle
			(at -0.40005 0 180)
			(size 0 0)
			(layers "F.Cu" "F.Mask" "F.Paste")
			(net "SMB_BMC_9ZXL0851_8_15_SCL")
		)
		(pad "2" smd circle
			(at 0.40005 0 180)
			(size 0 0)
			(layers "F.Cu" "F.Mask" "F.Paste")
			(net "SMB_ISO_CB_SCL")
		)
	)
	(footprint ""
		(layer "F.Cu")
		(at 434.02123 -311.3278 -90)
		(property "Reference" "R6722"
			(at 0 0 270)
			(layer "F.SilkS")
			(hide yes)
			(effects
				(font
					(size 1.27 1.27)
				)
			)
		)
		(property "Value" ""
			(at 0 0 270)
			(layer "F.Fab")
			(effects
				(font
					(size 1.27 1.27)
				)
			)
		)
		(duplicate_pad_numbers_are_jumpers no)
		(fp_line
			(start -0.7874 0.4064)
			(end -0.7874 -0.4064)
			(stroke
				(width 0.1524)
				(type default)
			)
			(layer "F.SilkS")
		)
		(fp_line
			(start 0.7874 0.4064)
			(end -0.7874 0.4064)
			(stroke
				(width 0.1524)
				(type default)
			)
			(layer "F.SilkS")
		)
		(fp_line
			(start -0.7874 -0.4064)
			(end 0.7874 -0.4064)
			(stroke
				(width 0.1524)
				(type default)
			)
			(layer "F.SilkS")
		)
		(fp_line
			(start 0.7874 -0.4064)
			(end 0.7874 0.4064)
			(stroke
				(width 0.1524)
				(type default)
			)
			(layer "F.SilkS")
		)
		(fp_line
			(start -0.67945 0.3048)
			(end -0.67945 -0.305054)
			(stroke
				(width 0.1)
				(type default)
			)
			(layer "F.Fab")
		)
		(fp_line
			(start -0.12065 0.3048)
			(end -0.67945 0.3048)
			(stroke
				(width 0.1)
				(type default)
			)
			(layer "F.Fab")
		)
		(fp_line
			(start 0.120396 0.3048)
			(end 0.120396 0.2794)
			(stroke
				(width 0.1)
				(type default)
			)
			(layer "F.Fab")
		)
		(fp_line
			(start 0.67945 0.3048)
			(end 0.120396 0.3048)
			(stroke
				(width 0.1)
				(type default)
			)
			(layer "F.Fab")
		)
		(fp_line
			(start -0.12065 0.2794)
			(end -0.12065 0.3048)
			(stroke
				(width 0.1)
				(type default)
			)
			(layer "F.Fab")
		)
		(fp_line
			(start 0.120396 0.2794)
			(end -0.12065 0.2794)
			(stroke
				(width 0.1)
				(type default)
			)
			(layer "F.Fab")
		)
		(fp_line
			(start -0.12065 -0.2794)
			(end 0.12065 -0.2794)
			(stroke
				(width 0.1)
				(type default)
			)
			(layer "F.Fab")
		)
		(fp_line
			(start 0.12065 -0.2794)
			(end 0.12065 -0.3048)
			(stroke
				(width 0.1)
				(type default)
			)
			(layer "F.Fab")
		)
		(fp_line
			(start 0.12065 -0.3048)
			(end 0.67945 -0.3048)
			(stroke
				(width 0.1)
				(type default)
			)
			(layer "F.Fab")
		)
		(fp_line
			(start 0.67945 -0.3048)
			(end 0.67945 0.3048)
			(stroke
				(width 0.1)
				(type default)
			)
			(layer "F.Fab")
		)
		(fp_line
			(start -0.67945 -0.305054)
			(end -0.12065 -0.305054)
			(stroke
				(width 0.1)
				(type default)
			)
			(layer "F.Fab")
		)
		(fp_line
			(start -0.12065 -0.305054)
			(end -0.12065 -0.2794)
			(stroke
				(width 0.1)
				(type default)
			)
			(layer "F.Fab")
		)
		(pad "1" smd circle
			(at -0.40005 0 270)
			(size 0 0)
			(layers "F.Cu" "F.Mask" "F.Paste")
			(net "SMB_PEX3_SLAVE1_SCL")
		)
		(pad "2" smd circle
			(at 0.40005 0 270)
			(size 0 0)
			(layers "F.Cu" "F.Mask" "F.Paste")
			(net "SMB_PEX3_R_SCL")
		)
	)
	(footprint ""
		(layer "F.Cu")
		(at 123.31319 -107.928918 -90)
		(property "Reference" "Q126"
			(at 0.423926 -1.964182 90)
			(unlocked yes)
			(layer "F.SilkS")
			(effects
				(font
					(size 0.7874 0.5842)
					(thickness 0.1524)
				)
			)
		)
		(property "Value" ""
			(at 0 0 270)
			(layer "F.Fab")
			(effects
				(font
					(size 1.27 1.27)
				)
			)
		)
		(duplicate_pad_numbers_are_jumpers no)
		(fp_line
			(start -1.376172 1.199896)
			(end -1.376172 -1.199896)
			(stroke
				(width 0.1524)
				(type default)
			)
			(layer "F.SilkS")
		)
		(fp_line
			(start 1.376172 1.199896)
			(end -1.376172 1.199896)
			(stroke
				(width 0.1524)
				(type default)
			)
			(layer "F.SilkS")
		)
		(fp_line
			(start 0 -0.762)
			(end 0.508 -1.199896)
			(stroke
				(width 0.1524)
				(type default)
			)
			(layer "F.SilkS")
		)
		(fp_line
			(start -1.376172 -1.199896)
			(end -0.508 -1.199896)
			(stroke
				(width 0.1524)
				(type default)
			)
			(layer "F.SilkS")
		)
		(fp_line
			(start -0.508 -1.199896)
			(end 0 -0.762)
			(stroke
				(width 0.1524)
				(type default)
			)
			(layer "F.SilkS")
		)
		(fp_line
			(start 0.508 -1.199896)
			(end 1.376172 -1.199896)
			(stroke
				(width 0.1524)
				(type default)
			)
			(layer "F.SilkS")
		)
		(fp_line
			(start 1.376172 -1.199896)
			(end 1.376172 1.199896)
			(stroke
				(width 0.1524)
				(type default)
			)
			(layer "F.SilkS")
		)
		(fp_poly
			(pts
				(xy -1.176274 -1.296924) (xy -1.445768 -2.105152) (xy -1.984502 -1.566418)
			)
			(stroke
				(width 0)
				(type default)
			)
			(fill yes)
			(layer "F.SilkS")
		)
		(fp_line
			(start -0.674878 1.100074)
			(end -0.674878 -1.100074)
			(stroke
				(width 0.1)
				(type default)
			)
			(layer "F.Fab")
		)
		(fp_line
			(start 0.674878 1.100074)
			(end -0.674878 1.100074)
			(stroke
				(width 0.1)
				(type default)
			)
			(layer "F.Fab")
		)
		(fp_line
			(start -0.674878 -1.100074)
			(end 0.674878 -1.100074)
			(stroke
				(width 0.1)
				(type default)
			)
			(layer "F.Fab")
		)
		(fp_line
			(start 0.674878 -1.100074)
			(end 0.674878 1.100074)
			(stroke
				(width 0.1)
				(type default)
			)
			(layer "F.Fab")
		)
		(fp_poly
			(pts
				(xy -1.4605 -0.7493) (xy -2.2225 -1.1303) (xy -2.2225 -0.3683)
			)
			(stroke
				(width 0)
				(type default)
			)
			(fill yes)
			(layer "F.Fab")
		)
		(pad "1" smd rect
			(at -0.899922 -0.750062 180)
			(size 0.6096 0.6096)
			(layers "F.Cu" "F.Mask" "F.Paste")
			(net "GND")
		)
		(pad "2" smd rect
			(at -0.899922 0 180)
			(size 0.4064 0.6096)
			(layers "F.Cu" "F.Mask" "F.Paste")
			(net "P3V3_PG_G1")
		)
		(pad "3" smd rect
			(at -0.899922 0.750062 180)
			(size 0.6096 0.6096)
			(layers "F.Cu" "F.Mask" "F.Paste")
			(net "PWRGD_P3V3_D")
		)
		(pad "4" smd rect
			(at 0.899922 0.750062 180)
			(size 0.6096 0.6096)
			(layers "F.Cu" "F.Mask" "F.Paste")
			(net "GND")
		)
		(pad "5" smd rect
			(at 0.899922 0 180)
			(size 0.4064 0.6096)
			(layers "F.Cu" "F.Mask" "F.Paste")
			(net "P3V3_PG_G2")
		)
		(pad "6" smd rect
			(at 0.899922 -0.750062 180)
			(size 0.6096 0.6096)
			(layers "F.Cu" "F.Mask" "F.Paste")
			(net "P3V3_PG_G2")
		)
	)
	(footprint ""
		(layer "F.Cu")
		(at 225.828606 -257.975862 -90)
		(property "Reference" "R6499"
			(at 0 0 270)
			(layer "F.SilkS")
			(hide yes)
			(effects
				(font
					(size 1.27 1.27)
				)
			)
		)
		(property "Value" ""
			(at 0 0 270)
			(layer "F.Fab")
			(effects
				(font
					(size 1.27 1.27)
				)
			)
		)
		(duplicate_pad_numbers_are_jumpers no)
		(fp_line
			(start -0.7874 0.4064)
			(end -0.7874 -0.4064)
			(stroke
				(width 0.1524)
				(type default)
			)
			(layer "F.SilkS")
		)
		(fp_line
			(start 0.7874 0.4064)
			(end -0.7874 0.4064)
			(stroke
				(width 0.1524)
				(type default)
			)
			(layer "F.SilkS")
		)
		(fp_line
			(start -0.7874 -0.4064)
			(end 0.7874 -0.4064)
			(stroke
				(width 0.1524)
				(type default)
			)
			(layer "F.SilkS")
		)
		(fp_line
			(start 0.7874 -0.4064)
			(end 0.7874 0.4064)
			(stroke
				(width 0.1524)
				(type default)
			)
			(layer "F.SilkS")
		)
		(fp_line
			(start -0.67945 0.3048)
			(end -0.67945 -0.305054)
			(stroke
				(width 0.1)
				(type default)
			)
			(layer "F.Fab")
		)
		(fp_line
			(start -0.12065 0.3048)
			(end -0.67945 0.3048)
			(stroke
				(width 0.1)
				(type default)
			)
			(layer "F.Fab")
		)
		(fp_line
			(start 0.120396 0.3048)
			(end 0.120396 0.2794)
			(stroke
				(width 0.1)
				(type default)
			)
			(layer "F.Fab")
		)
		(fp_line
			(start 0.67945 0.3048)
			(end 0.120396 0.3048)
			(stroke
				(width 0.1)
				(type default)
			)
			(layer "F.Fab")
		)
		(fp_line
			(start -0.12065 0.2794)
			(end -0.12065 0.3048)
			(stroke
				(width 0.1)
				(type default)
			)
			(layer "F.Fab")
		)
		(fp_line
			(start 0.120396 0.2794)
			(end -0.12065 0.2794)
			(stroke
				(width 0.1)
				(type default)
			)
			(layer "F.Fab")
		)
		(fp_line
			(start -0.12065 -0.2794)
			(end 0.12065 -0.2794)
			(stroke
				(width 0.1)
				(type default)
			)
			(layer "F.Fab")
		)
		(fp_line
			(start 0.12065 -0.2794)
			(end 0.12065 -0.3048)
			(stroke
				(width 0.1)
				(type default)
			)
			(layer "F.Fab")
		)
		(fp_line
			(start 0.12065 -0.3048)
			(end 0.67945 -0.3048)
			(stroke
				(width 0.1)
				(type default)
			)
			(layer "F.Fab")
		)
		(fp_line
			(start 0.67945 -0.3048)
			(end 0.67945 0.3048)
			(stroke
				(width 0.1)
				(type default)
			)
			(layer "F.Fab")
		)
		(fp_line
			(start -0.67945 -0.305054)
			(end -0.12065 -0.305054)
			(stroke
				(width 0.1)
				(type default)
			)
			(layer "F.Fab")
		)
		(fp_line
			(start -0.12065 -0.305054)
			(end -0.12065 -0.2794)
			(stroke
				(width 0.1)
				(type default)
			)
			(layer "F.Fab")
		)
		(pad "1" smd circle
			(at -0.40005 0 270)
			(size 0 0)
			(layers "F.Cu" "F.Mask" "F.Paste")
			(net "P1V25_SERDES_VDDPLL_PEX1")
		)
		(pad "2" smd circle
			(at 0.40005 0 270)
			(size 0 0)
			(layers "F.Cu" "F.Mask" "F.Paste")
			(net "P1V25_SERDES_VDDPLL_PEX1_C6")
		)
	)
	(footprint ""
		(layer "F.Cu")
		(at 80.019398 -134.394702 180)
		(property "Reference" "C19"
			(at 0 0 180)
			(layer "F.SilkS")
			(hide yes)
			(effects
				(font
					(size 1.27 1.27)
				)
			)
		)
		(property "Value" ""
			(at 0 0 180)
			(layer "F.Fab")
			(effects
				(font
					(size 1.27 1.27)
				)
			)
		)
		(duplicate_pad_numbers_are_jumpers no)
		(fp_line
			(start 0.299974 0.150114)
			(end -0.299974 0.150114)
			(stroke
				(width 0.1)
				(type default)
			)
			(layer "F.Fab")
		)
		(fp_line
			(start 0.299974 -0.150114)
			(end 0.299974 0.150114)
			(stroke
				(width 0.1)
				(type default)
			)
			(layer "F.Fab")
		)
		(fp_line
			(start -0.299974 0.150114)
			(end -0.299974 -0.150114)
			(stroke
				(width 0.1)
				(type default)
			)
			(layer "F.Fab")
		)
		(fp_line
			(start -0.299974 -0.150114)
			(end 0.299974 -0.150114)
			(stroke
				(width 0.1)
				(type default)
			)
			(layer "F.Fab")
		)
		(pad "1" smd rect
			(at -0.2667 0 180)
			(size 0.3048 0.381)
			(layers "F.Cu" "F.Mask" "F.Paste")
			(net "P5E_PEX0_STN0_TX_DP<6>")
		)
		(pad "2" smd rect
			(at 0.2667 0 180)
			(size 0.3048 0.381)
			(layers "F.Cu" "F.Mask" "F.Paste")
			(net "P5E_PEX0_STN0_TX_C_DP<6>")
		)
	)
)
